# BASEBOARD_FAB2 (Tioga Pass) — schematic netlist excerpt (pin names and nets, part order shuffled) for the footprints in the layout excerpt that follows; sources: Cadence DE-HDL packaged netlist, KiCad conversion of Wiwynn_Tioga_Pass_MB.brd

C8P15  CAP  100UF 4V 20% X5R  pkg 0805  page 76 : A = PVCCMCP_CPU1 ; B = GND
C9L11  CAP  10UF 16V 10% X6S  pkg 0805  page 227 : A = VR_FET_SW_P12V_STBY_PVDDQ_KLM ; B = GND
C8P13  CAP  47UF 4V 20% X6S  pkg 0805  page 76 : A = PVCCIN_CPU1 ; B = GND

(kicad_pcb
	(version 20260206)
	(generator "pcbnew")
	(generator_version "10.0")
	(general
		(thickness 1.6)
		(legacy_teardrops no)
	)
	(paper "A4")
	(title_block
		(title "Wiwynn_Tioga_Pass_MB.brd")
		(comment 1 "Tioga Pass / footprints 2712-2714 of 4770")
	)
	(layers
		(0 "F.Cu" signal "TOP")
		(4 "In1.Cu" signal "L2GND")
		(6 "In2.Cu" signal "L3")
		(8 "In3.Cu" signal "L4GND")
		(10 "In4.Cu" signal "L5")
		(12 "In5.Cu" signal "L6GND")
		(14 "In6.Cu" signal "L7VCC")
		(16 "In7.Cu" signal "L8VCC")
		(18 "In8.Cu" signal "L9GND")
		(20 "In9.Cu" signal "L10")
		(22 "In10.Cu" signal "L11GND")
		(24 "In11.Cu" signal "L12")
		(26 "In12.Cu" signal "L13GND")
		(2 "B.Cu" signal "BOTTOM")
		(9 "F.Adhes" user "F.Adhesive")
		(11 "B.Adhes" user "B.Adhesive")
		(13 "F.Paste" user "Package Geometry/Pastemask Top")
		(15 "B.Paste" user "Package Geometry/Pastemask Bottom")
		(5 "F.SilkS" user "Ref Des/Silkscreen Top")
		(7 "B.SilkS" user "Ref Des/Silkscreen Bottom")
		(1 "F.Mask" user "Board Geometry/Soldermask Top")
		(3 "B.Mask" user "Board Geometry/Soldermask Bottom")
		(17 "Dwgs.User" user "User.Drawings")
		(19 "Cmts.User" user "User.Comments")
		(21 "Eco1.User" user "User.Eco1")
		(23 "Eco2.User" user "User.Eco2")
		(25 "Edge.Cuts" user "Board Geometry/Outline")
		(27 "Margin" user)
		(31 "F.CrtYd" user "Package Geometry/Place Bound Top")
		(29 "B.CrtYd" user "Package Geometry/Place Bound Bottom")
		(35 "F.Fab" user "Ref Des/Assembly Top")
		(33 "B.Fab" user "Ref Des/Assembly Bottom")
	)
	(footprint ""
		(layer "B.Cu")
		(at 1.3462 -141.097 90)
		(property "Reference" "C9L11"
			(at 0 0 90)
			(layer "B.SilkS")
			(hide yes)
			(effects
				(font
					(size 1.27 1.27)
				)
				(justify mirror)
			)
		)
		(property "Value" ""
			(at 0 0 90)
			(layer "B.Fab")
			(effects
				(font
					(size 1.27 1.27)
				)
				(justify mirror)
			)
		)
		(duplicate_pad_numbers_are_jumpers no)
		(fp_rect
			(start -0.7239 -0.2159)
			(end 0.7239 1.9939)
			(stroke
				(width 0)
				(type default)
			)
			(fill no)
			(layer "B.CrtYd")
		)
		(fp_line
			(start 0.7239 -0.2159)
			(end 0.7239 1.9939)
			(stroke
				(width 0.1)
				(type default)
			)
			(layer "B.Fab")
		)
		(fp_line
			(start -0.7239 -0.2159)
			(end 0.7239 -0.2159)
			(stroke
				(width 0.1)
				(type default)
			)
			(layer "B.Fab")
		)
		(fp_line
			(start 0.7239 1.9939)
			(end -0.7239 1.9939)
			(stroke
				(width 0.1)
				(type default)
			)
			(layer "B.Fab")
		)
		(fp_line
			(start -0.7239 1.9939)
			(end -0.7239 -0.2159)
			(stroke
				(width 0.1)
				(type default)
			)
			(layer "B.Fab")
		)
		(pad "1" smd rect
			(at 0 0 270)
			(size 1.27 1.016)
			(layers "B.Cu" "B.Mask" "B.Paste")
			(net "VR_FET_SW_P12V_STBY_PVDDQ_KLM")
		)
		(pad "2" smd rect
			(at 0 1.778 270)
			(size 1.27 1.016)
			(layers "B.Cu" "B.Mask" "B.Paste")
			(net "GND")
		)
		(zone
			(layer "B.Cu")
			(hatch none 0.5)
			(connect_pads
				(clearance 0)
			)
			(min_thickness 0.25)
			(keepout
				(tracks not_allowed)
				(vias allowed)
				(pads allowed)
				(copperpour not_allowed)
				(footprints allowed)
			)
			(placement
				(enabled no)
				(sheetname "")
			)
			(fill
				(thermal_gap 0.5)
				(thermal_bridge_width 0.5)
				(island_removal_mode 0)
			)
			(polygon
				(pts
					(xy 1.8542 -140.462) (xy 2.6162 -140.462) (xy 2.6162 -141.732) (xy 1.8542 -141.732)
				)
			)
		)
	)
	(footprint ""
		(layer "B.Cu")
		(at 97.587054 -79.60614 180)
		(property "Reference" "C8P13"
			(at 0 0 0)
			(layer "B.SilkS")
			(hide yes)
			(effects
				(font
					(size 1.27 1.27)
				)
				(justify mirror)
			)
		)
		(property "Value" ""
			(at 0 0 0)
			(layer "B.Fab")
			(effects
				(font
					(size 1.27 1.27)
				)
				(justify mirror)
			)
		)
		(duplicate_pad_numbers_are_jumpers no)
		(fp_poly
			(pts
				(xy 0.7239 -0.2159) (xy -0.7239 -0.2159) (xy -0.7239 1.9939) (xy 0.7239 1.9939)
			)
			(stroke
				(width 0)
				(type default)
			)
			(fill no)
			(layer "B.CrtYd")
		)
		(fp_line
			(start 0.7239 1.9939)
			(end -0.7239 1.9939)
			(stroke
				(width 0.1)
				(type default)
			)
			(layer "B.Fab")
		)
		(fp_line
			(start 0.7239 -0.2159)
			(end 0.7239 1.9939)
			(stroke
				(width 0.1)
				(type default)
			)
			(layer "B.Fab")
		)
		(fp_line
			(start -0.7239 1.9939)
			(end -0.7239 -0.2159)
			(stroke
				(width 0.1)
				(type default)
			)
			(layer "B.Fab")
		)
		(fp_line
			(start -0.7239 -0.2159)
			(end 0.7239 -0.2159)
			(stroke
				(width 0.1)
				(type default)
			)
			(layer "B.Fab")
		)
		(pad "1" smd rect
			(at 0 0)
			(size 1.27 1.016)
			(layers "B.Cu" "B.Mask" "B.Paste")
			(net "PVCCIN_CPU1")
		)
		(pad "2" smd rect
			(at 0 1.778)
			(size 1.27 1.016)
			(layers "B.Cu" "B.Mask" "B.Paste")
			(net "GND")
		)
		(zone
			(layer "B.Cu")
			(hatch none 0.5)
			(connect_pads
				(clearance 0)
			)
			(min_thickness 0.25)
			(keepout
				(tracks not_allowed)
				(vias allowed)
				(pads allowed)
				(copperpour not_allowed)
				(footprints allowed)
			)
			(placement
				(enabled no)
				(sheetname "")
			)
			(fill
				(thermal_gap 0.5)
				(thermal_bridge_width 0.5)
				(island_removal_mode 0)
			)
			(polygon
				(pts
					(xy 96.952054 -80.11414) (xy 98.222054 -80.11414) (xy 98.222054 -80.87614) (xy 96.952054 -80.87614)
				)
			)
		)
	)
	(footprint ""
		(layer "B.Cu")
		(at 104.521254 -77.82814)
		(property "Reference" "C8P15"
			(at 0 0 0)
			(layer "B.SilkS")
			(hide yes)
			(effects
				(font
					(size 1.27 1.27)
				)
				(justify mirror)
			)
		)
		(property "Value" ""
			(at 0 0 0)
			(layer "B.Fab")
			(effects
				(font
					(size 1.27 1.27)
				)
				(justify mirror)
			)
		)
		(duplicate_pad_numbers_are_jumpers no)
		(fp_poly
			(pts
				(xy 0.7239 -0.2159) (xy -0.7239 -0.2159) (xy -0.7239 1.9939) (xy 0.7239 1.9939)
			)
			(stroke
				(width 0)
				(type default)
			)
			(fill no)
			(layer "B.CrtYd")
		)
		(fp_line
			(start -0.7239 -0.2159)
			(end 0.7239 -0.2159)
			(stroke
				(width 0.1)
				(type default)
			)
			(layer "B.Fab")
		)
		(fp_line
			(start -0.7239 1.9939)
			(end -0.7239 -0.2159)
			(stroke
				(width 0.1)
				(type default)
			)
			(layer "B.Fab")
		)
		(fp_line
			(start 0.7239 -0.2159)
			(end 0.7239 1.9939)
			(stroke
				(width 0.1)
				(type default)
			)
			(layer "B.Fab")
		)
		(fp_line
			(start 0.7239 1.9939)
			(end -0.7239 1.9939)
			(stroke
				(width 0.1)
				(type default)
			)
			(layer "B.Fab")
		)
		(pad "1" smd rect
			(at 0 0 180)
			(size 1.27 1.016)
			(layers "B.Cu" "B.Mask" "B.Paste")
			(net "PVCCMCP_CPU1")
		)
		(pad "2" smd rect
			(at 0 1.778 180)
			(size 1.27 1.016)
			(layers "B.Cu" "B.Mask" "B.Paste")
			(net "GND")
		)
		(zone
			(layer "B.Cu")
			(hatch none 0.5)
			(connect_pads
				(clearance 0)
			)
			(min_thickness 0.25)
			(keepout
				(tracks not_allowed)
				(vias allowed)
				(pads allowed)
				(copperpour not_allowed)
				(footprints allowed)
			)
			(placement
				(enabled no)
				(sheetname "")
			)
			(fill
				(thermal_gap 0.5)
				(thermal_bridge_width 0.5)
				(island_removal_mode 0)
			)
			(polygon
				(pts
					(xy 105.156254 -77.32014) (xy 103.886254 -77.32014) (xy 103.886254 -76.55814) (xy 105.156254 -76.55814)
				)
			)
		)
	)
)
